(kicad_pcb
	(version 20260206)
	(generator "pcbnew")
	(generator_version "10.0")
	(general
		(thickness 1.6)
		(legacy_teardrops no)
	)
	(paper "A4")
	(title_block
		(title "dpb — 14545-sa.0730WZS0815.brd")
		(comment 1 "Honey Badger (Wiwynn) / footprints 423-428 of 1066")
	)
	(layers
		(0 "F.Cu" signal "TOP")
		(4 "In1.Cu" signal "L2GND")
		(6 "In2.Cu" signal "L3")
		(8 "In3.Cu" signal "L4VCC")
		(10 "In4.Cu" signal "L5VCC")
		(12 "In5.Cu" signal "L6")
		(14 "In6.Cu" signal "L7GND")
		(2 "B.Cu" signal "BOTTOM")
		(9 "F.Adhes" user "F.Adhesive")
		(11 "B.Adhes" user "B.Adhesive")
		(13 "F.Paste" user "Package Geometry/Pastemask Top")
		(15 "B.Paste" user "Package Geometry/Pastemask Bottom")
		(5 "F.SilkS" user "Ref Des/Silkscreen Top")
		(7 "B.SilkS" user "Ref Des/Silkscreen Bottom")
		(1 "F.Mask" user "Board Geometry/Soldermask Top")
		(3 "B.Mask" user "Board Geometry/Soldermask Bottom")
		(17 "Dwgs.User" user "User.Drawings")
		(19 "Cmts.User" user "User.Comments")
		(21 "Eco1.User" user "User.Eco1")
		(23 "Eco2.User" user "User.Eco2")
		(25 "Edge.Cuts" user "Board Geometry/Outline")
		(27 "Margin" user)
		(31 "F.CrtYd" user "Package Geometry/Place Bound Top")
		(29 "B.CrtYd" user "Package Geometry/Place Bound Bottom")
		(35 "F.Fab" user "Ref Des/Assembly Top")
		(33 "B.Fab" user "Ref Des/Assembly Bottom")
	)
	(footprint ""
		(layer "F.Cu")
		(at 42.290746 -205.895702 180)
		(property "Reference" "R471"
			(at 0 0 180)
			(layer "F.SilkS")
			(hide yes)
			(effects
				(font
					(size 1.27 1.27)
				)
			)
		)
		(property "Value" "4K7R2J-2-GP"
			(at 0.064008 -3.993896 180)
			(unlocked yes)
			(layer "F.Fab")
			(hide yes)
			(effects
				(font
					(size 1.016 1.016)
					(thickness 0.1524)
				)
			)
		)
		(property "Device Type" "R402H16"
			(at 0.064008 -5.517896 180)
			(unlocked yes)
			(layer "F.Fab")
			(hide yes)
			(effects
				(font
					(size 1.016 1.016)
					(thickness 0.1524)
				)
			)
		)
		(duplicate_pad_numbers_are_jumpers no)
		(fp_line
			(start 0.508 -0.9398)
			(end -0.508 -0.9398)
			(stroke
				(width 0.1524)
				(type default)
			)
			(layer "F.SilkS")
		)
		(fp_line
			(start -0.508 -0.9398)
			(end -0.508 0.9398)
			(stroke
				(width 0.1524)
				(type default)
			)
			(layer "F.SilkS")
		)
		(fp_rect
			(start -0.508 0.9398)
			(end 0.508 -0.9398)
			(stroke
				(width 0)
				(type default)
			)
			(fill no)
			(layer "F.CrtYd")
		)
		(fp_rect
			(start -0.508 0.9398)
			(end 0.508 -0.9398)
			(stroke
				(width 0)
				(type default)
			)
			(fill no)
			(layer "F.Fab")
		)
		(pad "1" smd custom
			(at 0 -0.4445 180)
			(size 0.1397 0.1397)
			(layers "F.Cu" "F.Mask" "F.Paste")
			(net "P3V3")
			(options
				(clearance outline)
				(anchor circle)
			)
			(primitives
				(gr_poly
					(pts
						(arc
							(start -0.1778 -0.2794)
							(mid -0.249642 -0.249642)
							(end -0.2794 -0.1778)
						)
						(arc
							(start -0.2794 0.1778)
							(mid -0.249642 0.249642)
							(end -0.1778 0.2794)
						)
						(arc
							(start 0.1778 0.2794)
							(mid 0.249642 0.249642)
							(end 0.2794 0.1778)
						)
						(arc
							(start 0.2794 -0.1778)
							(mid 0.249642 -0.249642)
							(end 0.1778 -0.2794)
						)
					)
					(width 0)
					(fill yes)
				)
			)
		)
		(pad "2" smd custom
			(at 0 0.4445 180)
			(size 0.1397 0.1397)
			(layers "F.Cu" "F.Mask" "F.Paste")
			(net "SAS_EXP_B_PWR12")
			(options
				(clearance outline)
				(anchor circle)
			)
			(primitives
				(gr_poly
					(pts
						(arc
							(start -0.1778 -0.2794)
							(mid -0.249642 -0.249642)
							(end -0.2794 -0.1778)
						)
						(arc
							(start -0.2794 0.1778)
							(mid -0.249642 0.249642)
							(end -0.1778 0.2794)
						)
						(arc
							(start 0.1778 0.2794)
							(mid 0.249642 0.249642)
							(end 0.2794 0.1778)
						)
						(arc
							(start 0.2794 -0.1778)
							(mid 0.249642 -0.249642)
							(end 0.1778 -0.2794)
						)
					)
					(width 0)
					(fill yes)
				)
			)
		)
	)
	(footprint ""
		(layer "F.Cu")
		(at 58.039 -280.1874 90)
		(property "Reference" "R205"
			(at 0 0 90)
			(layer "F.SilkS")
			(hide yes)
			(effects
				(font
					(size 1.27 1.27)
				)
			)
		)
		(property "Value" "2R2010J-1-GP"
			(at 0.254 -8.0772 90)
			(unlocked yes)
			(layer "F.Fab")
			(hide yes)
			(effects
				(font
					(size 1.016 1.016)
					(thickness 0.1524)
				)
			)
		)
		(property "Device Type" "R2010H28"
			(at 0.254 -9.6774 90)
			(unlocked yes)
			(layer "F.Fab")
			(hide yes)
			(effects
				(font
					(size 1.016 1.016)
					(thickness 0.1524)
				)
			)
		)
		(duplicate_pad_numbers_are_jumpers no)
		(fp_line
			(start 1.651 -3.302)
			(end -1.651 -3.302)
			(stroke
				(width 0.1524)
				(type default)
			)
			(layer "F.SilkS")
		)
		(fp_line
			(start -1.651 -3.302)
			(end -1.651 3.302)
			(stroke
				(width 0.1524)
				(type default)
			)
			(layer "F.SilkS")
		)
		(fp_line
			(start 1.651 3.302)
			(end 1.651 -3.302)
			(stroke
				(width 0.1524)
				(type default)
			)
			(layer "F.SilkS")
		)
		(fp_line
			(start -1.651 3.302)
			(end 1.651 3.302)
			(stroke
				(width 0.1524)
				(type default)
			)
			(layer "F.SilkS")
		)
		(fp_rect
			(start -1.7272 -3.3782)
			(end 1.7272 3.3782)
			(stroke
				(width 0)
				(type default)
			)
			(fill no)
			(layer "F.CrtYd")
		)
		(fp_poly
			(pts
				(xy 1.7272 3.3782) (xy 1.7272 -3.3782) (xy -1.7272 -3.3782) (xy -1.7272 3.3782)
			)
			(stroke
				(width 0)
				(type default)
			)
			(fill no)
			(layer "F.Fab")
		)
		(pad "1" smd rect
			(at 0 -2.3495 90)
			(size 2.794 1.143)
			(layers "F.Cu" "F.Mask" "F.Paste")
			(net "5V_PRE_7")
		)
		(pad "2" smd rect
			(at 0 2.3495 90)
			(size 2.794 1.143)
			(layers "F.Cu" "F.Mask" "F.Paste")
			(net "P5V_HDD7")
		)
	)
	(footprint ""
		(layer "F.Cu")
		(at 73.431146 -6.632702)
		(property "Reference" "C338"
			(at 0 0 0)
			(layer "F.SilkS")
			(hide yes)
			(effects
				(font
					(size 1.27 1.27)
				)
			)
		)
		(property "Value" "SC1U25V3KX-1-GP"
			(at 0 -2.8194 0)
			(unlocked yes)
			(layer "F.Fab")
			(hide yes)
			(effects
				(font
					(size 1.016 1.016)
					(thickness 0.1524)
				)
			)
		)
		(property "Device Type" "C603H36"
			(at 0 -4.3434 0)
			(unlocked yes)
			(layer "F.Fab")
			(hide yes)
			(effects
				(font
					(size 1.016 1.016)
					(thickness 0.1524)
				)
			)
		)
		(duplicate_pad_numbers_are_jumpers no)
		(fp_line
			(start 0.508 0)
			(end -0.508 0)
			(stroke
				(width 0.2032)
				(type default)
			)
			(layer "F.SilkS")
		)
		(fp_rect
			(start -0.5842 1.3335)
			(end 0.5842 -1.3335)
			(stroke
				(width 0)
				(type default)
			)
			(fill no)
			(layer "F.CrtYd")
		)
		(fp_rect
			(start -0.5842 1.3335)
			(end 0.5842 -1.3335)
			(stroke
				(width 0)
				(type default)
			)
			(fill no)
			(layer "F.Fab")
		)
		(pad "1" smd custom
			(at 0 -0.762)
			(size 0.2159 0.2159)
			(layers "F.Cu" "F.Mask" "F.Paste")
			(net "P12V_HDD14")
			(options
				(clearance outline)
				(anchor circle)
			)
			(primitives
				(gr_poly
					(pts
						(arc
							(start -0.3302 -0.4318)
							(mid -0.402042 -0.402042)
							(end -0.4318 -0.3302)
						)
						(arc
							(start -0.4318 0.3302)
							(mid -0.402042 0.402042)
							(end -0.3302 0.4318)
						)
						(arc
							(start 0.3302 0.4318)
							(mid 0.402042 0.402042)
							(end 0.4318 0.3302)
						)
						(arc
							(start 0.4318 -0.3302)
							(mid 0.402042 -0.402042)
							(end 0.3302 -0.4318)
						)
					)
					(width 0)
					(fill yes)
				)
			)
		)
		(pad "2" smd custom
			(at 0 0.762)
			(size 0.2159 0.2159)
			(layers "F.Cu" "F.Mask" "F.Paste")
			(net "GND")
			(options
				(clearance outline)
				(anchor circle)
			)
			(primitives
				(gr_poly
					(pts
						(arc
							(start -0.3302 -0.4318)
							(mid -0.402042 -0.402042)
							(end -0.4318 -0.3302)
						)
						(arc
							(start -0.4318 0.3302)
							(mid -0.402042 0.402042)
							(end -0.3302 0.4318)
						)
						(arc
							(start 0.3302 0.4318)
							(mid 0.402042 0.402042)
							(end 0.4318 0.3302)
						)
						(arc
							(start 0.4318 -0.3302)
							(mid 0.402042 -0.402042)
							(end 0.3302 -0.4318)
						)
					)
					(width 0)
					(fill yes)
				)
			)
		)
	)
	(footprint ""
		(layer "F.Cu")
		(at 97.789746 -7.7597 90)
		(property "Reference" "R306"
			(at 0 0 90)
			(layer "F.SilkS")
			(hide yes)
			(effects
				(font
					(size 1.27 1.27)
				)
			)
		)
		(property "Value" "4K7R2J-2-GP"
			(at 0.064008 -3.993896 90)
			(unlocked yes)
			(layer "F.Fab")
			(hide yes)
			(effects
				(font
					(size 1.016 1.016)
					(thickness 0.1524)
				)
			)
		)
		(property "Device Type" "R402H16"
			(at 0.064008 -5.517896 90)
			(unlocked yes)
			(layer "F.Fab")
			(hide yes)
			(effects
				(font
					(size 1.016 1.016)
					(thickness 0.1524)
				)
			)
		)
		(duplicate_pad_numbers_are_jumpers no)
		(fp_line
			(start 0.508 -0.9398)
			(end -0.508 -0.9398)
			(stroke
				(width 0.1524)
				(type default)
			)
			(layer "F.SilkS")
		)
		(fp_line
			(start -0.508 -0.9398)
			(end -0.508 0.9398)
			(stroke
				(width 0.1524)
				(type default)
			)
			(layer "F.SilkS")
		)
		(fp_rect
			(start -0.508 0.9398)
			(end 0.508 -0.9398)
			(stroke
				(width 0)
				(type default)
			)
			(fill no)
			(layer "F.CrtYd")
		)
		(fp_rect
			(start -0.508 0.9398)
			(end 0.508 -0.9398)
			(stroke
				(width 0)
				(type default)
			)
			(fill no)
			(layer "F.Fab")
		)
		(pad "1" smd custom
			(at 0 -0.4445 90)
			(size 0.1397 0.1397)
			(layers "F.Cu" "F.Mask" "F.Paste")
			(net "P12V")
			(options
				(clearance outline)
				(anchor circle)
			)
			(primitives
				(gr_poly
					(pts
						(arc
							(start -0.1778 -0.2794)
							(mid -0.249642 -0.249642)
							(end -0.2794 -0.1778)
						)
						(arc
							(start -0.2794 0.1778)
							(mid -0.249642 0.249642)
							(end -0.1778 0.2794)
						)
						(arc
							(start 0.1778 0.2794)
							(mid 0.249642 0.249642)
							(end 0.2794 0.1778)
						)
						(arc
							(start 0.2794 -0.1778)
							(mid 0.249642 -0.249642)
							(end 0.1778 -0.2794)
						)
					)
					(width 0)
					(fill yes)
				)
			)
		)
		(pad "2" smd custom
			(at 0 0.4445 90)
			(size 0.1397 0.1397)
			(layers "F.Cu" "F.Mask" "F.Paste")
			(net "SW_HDD14_R")
			(options
				(clearance outline)
				(anchor circle)
			)
			(primitives
				(gr_poly
					(pts
						(arc
							(start -0.1778 -0.2794)
							(mid -0.249642 -0.249642)
							(end -0.2794 -0.1778)
						)
						(arc
							(start -0.2794 0.1778)
							(mid -0.249642 0.249642)
							(end -0.1778 0.2794)
						)
						(arc
							(start 0.1778 0.2794)
							(mid 0.249642 0.249642)
							(end 0.2794 0.1778)
						)
						(arc
							(start 0.2794 -0.1778)
							(mid 0.249642 -0.249642)
							(end 0.1778 -0.2794)
						)
					)
					(width 0)
					(fill yes)
				)
			)
		)
	)
	(footprint ""
		(layer "F.Cu")
		(at 48.208946 -40.9448 90)
		(property "Reference" "Q43"
			(at 0 0 90)
			(layer "F.SilkS")
			(hide yes)
			(effects
				(font
					(size 1.27 1.27)
				)
			)
		)
		(property "Value" "PMBS3904-1-GP"
			(at 0 -9.0932 90)
			(unlocked yes)
			(layer "F.Fab")
			(hide yes)
			(effects
				(font
					(size 1.016 1.016)
					(thickness 0.1524)
				)
			)
		)
		(property "Device Type" "SOT-23-10H44"
			(at 0 -10.6172 90)
			(unlocked yes)
			(layer "F.Fab")
			(hide yes)
			(effects
				(font
					(size 1.016 1.016)
					(thickness 0.1524)
				)
			)
		)
		(duplicate_pad_numbers_are_jumpers no)
		(fp_line
			(start 1.651 -1.778)
			(end -1.651 -1.778)
			(stroke
				(width 0.1524)
				(type default)
			)
			(layer "F.SilkS")
		)
		(fp_line
			(start -1.651 -1.778)
			(end -1.651 1.778)
			(stroke
				(width 0.1524)
				(type default)
			)
			(layer "F.SilkS")
		)
		(fp_line
			(start 1.651 1.778)
			(end 1.651 -1.778)
			(stroke
				(width 0.1524)
				(type default)
			)
			(layer "F.SilkS")
		)
		(fp_line
			(start -1.651 1.778)
			(end 1.651 1.778)
			(stroke
				(width 0.1524)
				(type default)
			)
			(layer "F.SilkS")
		)
		(fp_line
			(start -0.9906 1.86309)
			(end -0.701294 2.15265)
			(stroke
				(width 0.0127)
				(type default)
			)
			(layer "F.SilkS")
		)
		(fp_line
			(start -0.994156 1.8669)
			(end -0.987044 1.8669)
			(stroke
				(width 0.0127)
				(type default)
			)
			(layer "F.SilkS")
		)
		(fp_line
			(start -1.003808 1.876552)
			(end -0.977646 1.876552)
			(stroke
				(width 0.0127)
				(type default)
			)
			(layer "F.SilkS")
		)
		(fp_line
			(start -0.635 1.8796)
			(end -1.7526 1.8796)
			(stroke
				(width 0.3302)
				(type default)
			)
			(layer "F.SilkS")
		)
		(fp_line
			(start -1.7526 1.8796)
			(end -1.7526 0.9906)
			(stroke
				(width 0.3302)
				(type default)
			)
			(layer "F.SilkS")
		)
		(fp_line
			(start -1.013206 1.88595)
			(end -0.967994 1.88595)
			(stroke
				(width 0.0127)
				(type default)
			)
			(layer "F.SilkS")
		)
		(fp_line
			(start -1.022858 1.895602)
			(end -0.958596 1.895602)
			(stroke
				(width 0.0127)
				(type default)
			)
			(layer "F.SilkS")
		)
		(fp_line
			(start -1.032256 1.905)
			(end -0.948944 1.905)
			(stroke
				(width 0.0127)
				(type default)
			)
			(layer "F.SilkS")
		)
		(fp_line
			(start -1.041908 1.914652)
			(end -0.939546 1.914652)
			(stroke
				(width 0.0127)
				(type default)
			)
			(layer "F.SilkS")
		)
		(fp_line
			(start -1.051306 1.92405)
			(end -0.929894 1.92405)
			(stroke
				(width 0.0127)
				(type default)
			)
			(layer "F.SilkS")
		)
		(fp_line
			(start -1.060958 1.933702)
			(end -0.920496 1.933702)
			(stroke
				(width 0.0127)
				(type default)
			)
			(layer "F.SilkS")
		)
		(fp_line
			(start -1.070356 1.9431)
			(end -0.910844 1.9431)
			(stroke
				(width 0.0127)
				(type default)
			)
			(layer "F.SilkS")
		)
		(fp_line
			(start -1.080008 1.952752)
			(end -0.901446 1.952752)
			(stroke
				(width 0.0127)
				(type default)
			)
			(layer "F.SilkS")
		)
		(fp_line
			(start -1.089406 1.96215)
			(end -0.891794 1.96215)
			(stroke
				(width 0.0127)
				(type default)
			)
			(layer "F.SilkS")
		)
		(fp_line
			(start -1.099058 1.971802)
			(end -0.882396 1.971802)
			(stroke
				(width 0.0127)
				(type default)
			)
			(layer "F.SilkS")
		)
		(fp_line
			(start -1.108456 1.9812)
			(end -0.872744 1.9812)
			(stroke
				(width 0.0127)
				(type default)
			)
			(layer "F.SilkS")
		)
		(fp_line
			(start -1.118108 1.990852)
			(end -0.863346 1.990852)
			(stroke
				(width 0.0127)
				(type default)
			)
			(layer "F.SilkS")
		)
		(fp_line
			(start -1.127506 2.00025)
			(end -0.853694 2.00025)
			(stroke
				(width 0.0127)
				(type default)
			)
			(layer "F.SilkS")
		)
		(fp_line
			(start -1.137158 2.009902)
			(end -0.844296 2.009902)
			(stroke
				(width 0.0127)
				(type default)
			)
			(layer "F.SilkS")
		)
		(fp_line
			(start -1.146556 2.0193)
			(end -0.834644 2.0193)
			(stroke
				(width 0.0127)
				(type default)
			)
			(layer "F.SilkS")
		)
		(fp_line
			(start -1.156208 2.028952)
			(end -0.825246 2.028952)
			(stroke
				(width 0.0127)
				(type default)
			)
			(layer "F.SilkS")
		)
		(fp_line
			(start -1.165606 2.03835)
			(end -0.815594 2.03835)
			(stroke
				(width 0.0127)
				(type default)
			)
			(layer "F.SilkS")
		)
		(fp_line
			(start -1.175258 2.048002)
			(end -0.806196 2.048002)
			(stroke
				(width 0.0127)
				(type default)
			)
			(layer "F.SilkS")
		)
		(fp_line
			(start -1.184656 2.0574)
			(end -0.796544 2.0574)
			(stroke
				(width 0.0127)
				(type default)
			)
			(layer "F.SilkS")
		)
		(fp_line
			(start -1.194308 2.067052)
			(end -0.787146 2.067052)
			(stroke
				(width 0.0127)
				(type default)
			)
			(layer "F.SilkS")
		)
		(fp_line
			(start -1.203706 2.07645)
			(end -0.777494 2.07645)
			(stroke
				(width 0.0127)
				(type default)
			)
			(layer "F.SilkS")
		)
		(fp_line
			(start -1.213358 2.086102)
			(end -0.768096 2.086102)
			(stroke
				(width 0.0127)
				(type default)
			)
			(layer "F.SilkS")
		)
		(fp_line
			(start -1.222756 2.0955)
			(end -0.758444 2.0955)
			(stroke
				(width 0.0127)
				(type default)
			)
			(layer "F.SilkS")
		)
		(fp_line
			(start -1.232408 2.105152)
			(end -0.749046 2.105152)
			(stroke
				(width 0.0127)
				(type default)
			)
			(layer "F.SilkS")
		)
		(fp_line
			(start -1.241806 2.11455)
			(end -0.739394 2.11455)
			(stroke
				(width 0.0127)
				(type default)
			)
			(layer "F.SilkS")
		)
		(fp_line
			(start -1.251458 2.124202)
			(end -0.729996 2.124202)
			(stroke
				(width 0.0127)
				(type default)
			)
			(layer "F.SilkS")
		)
		(fp_line
			(start -1.260856 2.1336)
			(end -0.720344 2.1336)
			(stroke
				(width 0.0127)
				(type default)
			)
			(layer "F.SilkS")
		)
		(fp_line
			(start -0.719074 2.145538)
			(end -1.265936 2.14122)
			(stroke
				(width 0.0127)
				(type default)
			)
			(layer "F.SilkS")
		)
		(fp_line
			(start -1.279398 2.152142)
			(end -0.9906 1.86309)
			(stroke
				(width 0.0127)
				(type default)
			)
			(layer "F.SilkS")
		)
		(fp_line
			(start -0.71628 2.15265)
			(end -1.26492 2.15265)
			(stroke
				(width 0.0127)
				(type default)
			)
			(layer "F.SilkS")
		)
		(fp_line
			(start -1.279144 2.15265)
			(end -0.701294 2.15265)
			(stroke
				(width 0.0127)
				(type default)
			)
			(layer "F.SilkS")
		)
		(fp_poly
			(pts
				(xy -1.285748 2.159) (xy -1.285748 1.8796) (xy -1.778 1.8796) (xy -1.778 -1.8796) (xy 1.778 -1.8796)
				(xy 1.778 1.8796) (xy -0.694944 1.8796) (xy -0.694944 2.159)
			)
			(stroke
				(width 0)
				(type default)
			)
			(fill no)
			(layer "F.CrtYd")
		)
		(fp_poly
			(pts
				(xy -1.285748 2.159) (xy -1.285748 1.8796) (xy -1.778 1.8796) (xy -1.778 -1.8796) (xy 1.778 -1.8796)
				(xy 1.778 1.8796) (xy -0.694944 1.8796) (xy -0.694944 2.159)
			)
			(stroke
				(width 0)
				(type default)
			)
			(fill no)
			(layer "F.Fab")
		)
		(pad "1" smd rect
			(at -0.98425 0.9525 90)
			(size 0.762 1.143)
			(layers "F.Cu" "F.Mask" "F.Paste")
			(net "FLT_HDD9_B")
		)
		(pad "2" smd rect
			(at 0.98425 0.9525 90)
			(size 0.762 1.143)
			(layers "F.Cu" "F.Mask" "F.Paste")
			(net "GND")
		)
		(pad "3" smd rect
			(at 0 -0.9525 90)
			(size 0.762 1.143)
			(layers "F.Cu" "F.Mask" "F.Paste")
			(net "DRIVE_ACT_9")
		)
	)
	(footprint ""
		(layer "F.Cu")
		(at 205.74 -175.006)
		(property "Reference" "C367"
			(at 0 0 0)
			(layer "F.SilkS")
			(hide yes)
			(effects
				(font
					(size 1.27 1.27)
				)
			)
		)
		(property "Value" "SCD033U25V2KX-GP"
			(at 1.1811 -2.7051 0)
			(unlocked yes)
			(layer "F.Fab")
			(hide yes)
			(effects
				(font
					(size 1.016 1.016)
					(thickness 0.1524)
				)
			)
		)
		(property "Device Type" "C402H22"
			(at 1.1811 -4.2291 0)
			(unlocked yes)
			(layer "F.Fab")
			(hide yes)
			(effects
				(font
					(size 1.016 1.016)
					(thickness 0.1524)
				)
			)
		)
		(duplicate_pad_numbers_are_jumpers no)
		(fp_rect
			(start -0.4318 0.9525)
			(end 0.4318 -0.9525)
			(stroke
				(width 0)
				(type default)
			)
			(fill no)
			(layer "F.CrtYd")
		)
		(fp_rect
			(start -0.4318 0.9525)
			(end 0.4318 -0.9525)
			(stroke
				(width 0)
				(type default)
			)
			(fill no)
			(layer "F.Fab")
		)
		(pad "1" smd custom
			(at 0 -0.4445)
			(size 0.1524 0.1524)
			(layers "F.Cu" "F.Mask" "F.Paste")
			(net "SW_HDD3_P")
			(options
				(clearance outline)
				(anchor circle)
			)
			(primitives
				(gr_poly
					(pts
						(arc
							(start 0.3048 -0.2032)
							(mid 0.275042 -0.275042)
							(end 0.2032 -0.3048)
						)
						(arc
							(start -0.2032 -0.3048)
							(mid -0.275042 -0.275042)
							(end -0.3048 -0.2032)
						)
						(arc
							(start -0.3048 0.2032)
							(mid -0.275042 0.275042)
							(end -0.2032 0.3048)
						)
						(arc
							(start 0.2032 0.3048)
							(mid 0.275042 0.275042)
							(end 0.3048 0.2032)
						)
					)
					(width 0)
					(fill yes)
				)
			)
		)
		(pad "2" smd custom
			(at 0 0.4445)
			(size 0.1524 0.1524)
			(layers "F.Cu" "F.Mask" "F.Paste")
			(net "GND")
			(options
				(clearance outline)
				(anchor circle)
			)
			(primitives
				(gr_poly
					(pts
						(arc
							(start 0.3048 -0.2032)
							(mid 0.275042 -0.275042)
							(end 0.2032 -0.3048)
						)
						(arc
							(start -0.2032 -0.3048)
							(mid -0.275042 -0.275042)
							(end -0.3048 -0.2032)
						)
						(arc
							(start -0.3048 0.2032)
							(mid -0.275042 0.275042)
							(end -0.2032 0.3048)
						)
						(arc
							(start 0.2032 0.3048)
							(mid 0.275042 0.275042)
							(end 0.3048 0.2032)
						)
					)
					(width 0)
					(fill yes)
				)
			)
		)
	)
)
